(kicad_pcb
	(version 20260206)
	(generator "pcbnew")
	(generator_version "10.0")
	(general
		(thickness 1.6)
		(legacy_teardrops no)
	)
	(paper "A4")
	(title_block
		(title "04192023_DAF0TMB3IC0_F0TG_MB_C_brd_V02_OCP.brd")
		(comment 1 "Grand Teton / footprint 583 of 8354 (J27), pads 227-291 of 291")
	)
	(layers
		(0 "F.Cu" signal "TOP")
		(4 "In1.Cu" signal "GND")
		(6 "In2.Cu" signal "IN1")
		(8 "In3.Cu" signal "GND1")
		(10 "In4.Cu" signal "IN2")
		(12 "In5.Cu" signal "GND2")
		(14 "In6.Cu" signal "IN3")
		(16 "In7.Cu" signal "GND3")
		(18 "In8.Cu" signal "VCC")
		(20 "In9.Cu" signal "VCC1")
		(22 "In10.Cu" signal "GND4")
		(24 "In11.Cu" signal "IN4")
		(26 "In12.Cu" signal "GND5")
		(28 "In13.Cu" signal "IN5")
		(30 "In14.Cu" signal "GND6")
		(32 "In15.Cu" signal "IN6")
		(34 "In16.Cu" signal "GND7")
		(2 "B.Cu" signal "BOTTOM")
		(9 "F.Adhes" user "F.Adhesive")
		(11 "B.Adhes" user "B.Adhesive")
		(13 "F.Paste" user "Package Geometry/Pastemask Top")
		(15 "B.Paste" user "Package Geometry/Pastemask Bottom")
		(5 "F.SilkS" user "Ref Des/Silkscreen Top")
		(7 "B.SilkS" user "Ref Des/Silkscreen Bottom")
		(1 "F.Mask" user "Board Geometry/Soldermask Top")
		(3 "B.Mask" user "Board Geometry/Soldermask Bottom")
		(17 "Dwgs.User" user "User.Drawings")
		(19 "Cmts.User" user "User.Comments")
		(21 "Eco1.User" user "User.Eco1")
		(23 "Eco2.User" user "User.Eco2")
		(25 "Edge.Cuts" user "Board Geometry/Outline")
		(27 "Margin" user)
		(31 "F.CrtYd" user "Package Geometry/Place Bound Top")
		(29 "B.CrtYd" user "Package Geometry/Place Bound Bottom")
		(35 "F.Fab" user "Ref Des/Assembly Top")
		(33 "B.Fab" user "Ref Des/Assembly Bottom")
	)
	(footprint ""
		(layer "F.Cu")
		(at 174.022004 -255.560322 180)
		(property "Reference" "J27"
			(at -2.7178 -81.857088 0)
			(unlocked yes)
			(layer "F.SilkS")
			(effects
				(font
					(size 0.7874 0.5842)
					(thickness 0.1524)
				)
			)
		)
		(property "Value" ""
			(at 0 0 180)
			(layer "F.Fab")
			(effects
				(font
					(size 1.27 1.27)
				)
			)
		)
		(duplicate_pad_numbers_are_jumpers no)
		(pad "227" smd rect
			(at 2.050034 11.474958 90)
			(size 0.519938 1.4986)
			(layers "F.Cu" "F.Mask" "F.Paste")
			(net "M_H_CPU1_SB_PAR")
		)
		(pad "228" smd rect
			(at 2.050034 12.325096 90)
			(size 0.519938 1.4986)
			(layers "F.Cu" "F.Mask" "F.Paste")
			(net "GND")
		)
		(pad "229" smd rect
			(at 2.050034 13.17498 90)
			(size 0.519938 1.4986)
			(layers "F.Cu" "F.Mask" "F.Paste")
			(net "M_H_CPU1_SB_CS_N<1>")
		)
		(pad "230" smd rect
			(at 2.050034 14.025118 90)
			(size 0.519938 1.4986)
			(layers "F.Cu" "F.Mask" "F.Paste")
			(net "GND")
		)
		(pad "231" smd rect
			(at 2.050034 14.875002 90)
			(size 0.519938 1.4986)
			(layers "F.Cu" "F.Mask" "F.Paste")
			(net "Net_2359")
		)
		(pad "232" smd rect
			(at 2.050034 15.724886 90)
			(size 0.519938 1.4986)
			(layers "F.Cu" "F.Mask" "F.Paste")
			(net "Net_2360")
		)
		(pad "233" smd rect
			(at 2.050034 16.575024 90)
			(size 0.519938 1.4986)
			(layers "F.Cu" "F.Mask" "F.Paste")
			(net "GND")
		)
		(pad "234" smd rect
			(at 2.050034 17.424908 90)
			(size 0.519938 1.4986)
			(layers "F.Cu" "F.Mask" "F.Paste")
			(net "M_H_CPU1_SB_CB<6>")
		)
		(pad "235" smd rect
			(at 2.050034 18.275046 90)
			(size 0.519938 1.4986)
			(layers "F.Cu" "F.Mask" "F.Paste")
			(net "GND")
		)
		(pad "236" smd rect
			(at 2.050034 19.12493 90)
			(size 0.519938 1.4986)
			(layers "F.Cu" "F.Mask" "F.Paste")
			(net "M_H_CPU1_SB_CB<7>")
		)
		(pad "237" smd rect
			(at 2.050034 19.975068 90)
			(size 0.519938 1.4986)
			(layers "F.Cu" "F.Mask" "F.Paste")
			(net "GND")
		)
		(pad "238" smd rect
			(at 2.050034 20.824952 90)
			(size 0.519938 1.4986)
			(layers "F.Cu" "F.Mask" "F.Paste")
			(net "M_H_CPU1_SB_DQS_DN<4>")
		)
		(pad "239" smd rect
			(at 2.050034 21.67509 90)
			(size 0.519938 1.4986)
			(layers "F.Cu" "F.Mask" "F.Paste")
			(net "M_H_CPU1_SB_DQS_DP<4>")
		)
		(pad "240" smd rect
			(at 2.050034 22.524974 90)
			(size 0.519938 1.4986)
			(layers "F.Cu" "F.Mask" "F.Paste")
			(net "GND")
		)
		(pad "241" smd rect
			(at 2.050034 23.375112 90)
			(size 0.519938 1.4986)
			(layers "F.Cu" "F.Mask" "F.Paste")
			(net "M_H_CPU1_SB_CB<2>")
		)
		(pad "242" smd rect
			(at 2.050034 24.224996 90)
			(size 0.519938 1.4986)
			(layers "F.Cu" "F.Mask" "F.Paste")
			(net "GND")
		)
		(pad "243" smd rect
			(at 2.050034 25.07488 90)
			(size 0.519938 1.4986)
			(layers "F.Cu" "F.Mask" "F.Paste")
			(net "M_H_CPU1_SB_CB<3>")
		)
		(pad "244" smd rect
			(at 2.050034 25.925018 90)
			(size 0.519938 1.4986)
			(layers "F.Cu" "F.Mask" "F.Paste")
			(net "GND")
		)
		(pad "245" smd rect
			(at 2.050034 26.774902 90)
			(size 0.519938 1.4986)
			(layers "F.Cu" "F.Mask" "F.Paste")
			(net "M_H_CPU1_SB_DQ<2>")
		)
		(pad "246" smd rect
			(at 2.050034 27.62504 90)
			(size 0.519938 1.4986)
			(layers "F.Cu" "F.Mask" "F.Paste")
			(net "GND")
		)
		(pad "247" smd rect
			(at 2.050034 28.474924 90)
			(size 0.519938 1.4986)
			(layers "F.Cu" "F.Mask" "F.Paste")
			(net "M_H_CPU1_SB_DQ<3>")
		)
		(pad "248" smd rect
			(at 2.050034 29.325062 90)
			(size 0.519938 1.4986)
			(layers "F.Cu" "F.Mask" "F.Paste")
			(net "GND")
		)
		(pad "249" smd rect
			(at 2.050034 30.174946 90)
			(size 0.519938 1.4986)
			(layers "F.Cu" "F.Mask" "F.Paste")
			(net "M_H_CPU1_SB_DQS_DN<5>")
		)
		(pad "250" smd rect
			(at 2.050034 31.025084 90)
			(size 0.519938 1.4986)
			(layers "F.Cu" "F.Mask" "F.Paste")
			(net "M_H_CPU1_SB_DQS_DP<5>")
		)
		(pad "251" smd rect
			(at 2.050034 31.874968 90)
			(size 0.519938 1.4986)
			(layers "F.Cu" "F.Mask" "F.Paste")
			(net "GND")
		)
		(pad "252" smd rect
			(at 2.050034 32.725106 90)
			(size 0.519938 1.4986)
			(layers "F.Cu" "F.Mask" "F.Paste")
			(net "M_H_CPU1_SB_DQ<6>")
		)
		(pad "253" smd rect
			(at 2.050034 33.57499 90)
			(size 0.519938 1.4986)
			(layers "F.Cu" "F.Mask" "F.Paste")
			(net "GND")
		)
		(pad "254" smd rect
			(at 2.050034 34.425128 90)
			(size 0.519938 1.4986)
			(layers "F.Cu" "F.Mask" "F.Paste")
			(net "M_H_CPU1_SB_DQ<7>")
		)
		(pad "255" smd rect
			(at 2.050034 35.275012 90)
			(size 0.519938 1.4986)
			(layers "F.Cu" "F.Mask" "F.Paste")
			(net "GND")
		)
		(pad "256" smd rect
			(at 2.050034 36.124896 90)
			(size 0.519938 1.4986)
			(layers "F.Cu" "F.Mask" "F.Paste")
			(net "M_H_CPU1_SB_DQ<10>")
		)
		(pad "257" smd rect
			(at 2.050034 36.975034 90)
			(size 0.519938 1.4986)
			(layers "F.Cu" "F.Mask" "F.Paste")
			(net "GND")
		)
		(pad "258" smd rect
			(at 2.050034 37.824918 90)
			(size 0.519938 1.4986)
			(layers "F.Cu" "F.Mask" "F.Paste")
			(net "M_H_CPU1_SB_DQ<11>")
		)
		(pad "259" smd rect
			(at 2.050034 38.675056 90)
			(size 0.519938 1.4986)
			(layers "F.Cu" "F.Mask" "F.Paste")
			(net "GND")
		)
		(pad "260" smd rect
			(at 2.050034 39.52494 90)
			(size 0.519938 1.4986)
			(layers "F.Cu" "F.Mask" "F.Paste")
			(net "M_H_CPU1_SB_DQS_DN<6>")
		)
		(pad "261" smd rect
			(at 2.050034 40.375078 90)
			(size 0.519938 1.4986)
			(layers "F.Cu" "F.Mask" "F.Paste")
			(net "M_H_CPU1_SB_DQS_DP<6>")
		)
		(pad "262" smd rect
			(at 2.050034 41.224962 90)
			(size 0.519938 1.4986)
			(layers "F.Cu" "F.Mask" "F.Paste")
			(net "GND")
		)
		(pad "263" smd rect
			(at 2.050034 42.0751 90)
			(size 0.519938 1.4986)
			(layers "F.Cu" "F.Mask" "F.Paste")
			(net "M_H_CPU1_SB_DQ<14>")
		)
		(pad "264" smd rect
			(at 2.050034 42.924984 90)
			(size 0.519938 1.4986)
			(layers "F.Cu" "F.Mask" "F.Paste")
			(net "GND")
		)
		(pad "265" smd rect
			(at 2.050034 43.775122 90)
			(size 0.519938 1.4986)
			(layers "F.Cu" "F.Mask" "F.Paste")
			(net "M_H_CPU1_SB_DQ<15>")
		)
		(pad "266" smd rect
			(at 2.050034 44.625006 90)
			(size 0.519938 1.4986)
			(layers "F.Cu" "F.Mask" "F.Paste")
			(net "GND")
		)
		(pad "267" smd rect
			(at 2.050034 45.47489 90)
			(size 0.519938 1.4986)
			(layers "F.Cu" "F.Mask" "F.Paste")
			(net "M_H_CPU1_SB_DQ<18>")
		)
		(pad "268" smd rect
			(at 2.050034 46.325028 90)
			(size 0.519938 1.4986)
			(layers "F.Cu" "F.Mask" "F.Paste")
			(net "GND")
		)
		(pad "269" smd rect
			(at 2.050034 47.174912 90)
			(size 0.519938 1.4986)
			(layers "F.Cu" "F.Mask" "F.Paste")
			(net "M_H_CPU1_SB_DQ<19>")
		)
		(pad "270" smd rect
			(at 2.050034 48.02505 90)
			(size 0.519938 1.4986)
			(layers "F.Cu" "F.Mask" "F.Paste")
			(net "GND")
		)
		(pad "271" smd rect
			(at 2.050034 48.874934 90)
			(size 0.519938 1.4986)
			(layers "F.Cu" "F.Mask" "F.Paste")
			(net "M_H_CPU1_SB_DQS_DN<7>")
		)
		(pad "272" smd rect
			(at 2.050034 49.725072 90)
			(size 0.519938 1.4986)
			(layers "F.Cu" "F.Mask" "F.Paste")
			(net "M_H_CPU1_SB_DQS_DP<7>")
		)
		(pad "273" smd rect
			(at 2.050034 50.574956 90)
			(size 0.519938 1.4986)
			(layers "F.Cu" "F.Mask" "F.Paste")
			(net "GND")
		)
		(pad "274" smd rect
			(at 2.050034 51.425094 90)
			(size 0.519938 1.4986)
			(layers "F.Cu" "F.Mask" "F.Paste")
			(net "M_H_CPU1_SB_DQ<22>")
		)
		(pad "275" smd rect
			(at 2.050034 52.274978 90)
			(size 0.519938 1.4986)
			(layers "F.Cu" "F.Mask" "F.Paste")
			(net "GND")
		)
		(pad "276" smd rect
			(at 2.050034 53.125116 90)
			(size 0.519938 1.4986)
			(layers "F.Cu" "F.Mask" "F.Paste")
			(net "M_H_CPU1_SB_DQ<23>")
		)
		(pad "277" smd rect
			(at 2.050034 53.975 90)
			(size 0.519938 1.4986)
			(layers "F.Cu" "F.Mask" "F.Paste")
			(net "GND")
		)
		(pad "278" smd rect
			(at 2.050034 54.824884 90)
			(size 0.519938 1.4986)
			(layers "F.Cu" "F.Mask" "F.Paste")
			(net "M_H_CPU1_SB_DQ<26>")
		)
		(pad "279" smd rect
			(at 2.050034 55.675022 90)
			(size 0.519938 1.4986)
			(layers "F.Cu" "F.Mask" "F.Paste")
			(net "GND")
		)
		(pad "280" smd rect
			(at 2.050034 56.524906 90)
			(size 0.519938 1.4986)
			(layers "F.Cu" "F.Mask" "F.Paste")
			(net "M_H_CPU1_SB_DQ<27>")
		)
		(pad "281" smd rect
			(at 2.050034 57.375044 90)
			(size 0.519938 1.4986)
			(layers "F.Cu" "F.Mask" "F.Paste")
			(net "GND")
		)
		(pad "282" smd rect
			(at 2.050034 58.224928 90)
			(size 0.519938 1.4986)
			(layers "F.Cu" "F.Mask" "F.Paste")
			(net "M_H_CPU1_SB_DQS_DN<8>")
		)
		(pad "283" smd rect
			(at 2.050034 59.075066 90)
			(size 0.519938 1.4986)
			(layers "F.Cu" "F.Mask" "F.Paste")
			(net "M_H_CPU1_SB_DQS_DP<8>")
		)
		(pad "284" smd rect
			(at 2.050034 59.92495 90)
			(size 0.519938 1.4986)
			(layers "F.Cu" "F.Mask" "F.Paste")
			(net "GND")
		)
		(pad "285" smd rect
			(at 2.050034 60.775088 90)
			(size 0.519938 1.4986)
			(layers "F.Cu" "F.Mask" "F.Paste")
			(net "M_H_CPU1_SB_DQ<30>")
		)
		(pad "286" smd rect
			(at 2.050034 61.624972 90)
			(size 0.519938 1.4986)
			(layers "F.Cu" "F.Mask" "F.Paste")
			(net "GND")
		)
		(pad "287" smd rect
			(at 2.050034 62.47511 90)
			(size 0.519938 1.4986)
			(layers "F.Cu" "F.Mask" "F.Paste")
			(net "M_H_CPU1_SB_DQ<31>")
		)
		(pad "288" smd rect
			(at 2.050034 63.324994 90)
			(size 0.519938 1.4986)
			(layers "F.Cu" "F.Mask" "F.Paste")
			(net "GND")
		)
		(pad "G1" thru_hole oval
			(at 0 -68.97497 90)
			(size 1.7272 3.4798)
			(drill oval 1.2192 2.4638)
			(layers "*.Cu" "*.Mask")
			(remove_unused_layers no)
			(net "GND")
			(clearance 0.127)
			(thermal_gap 0.127)
		)
		(pad "G2" thru_hole oval
			(at 0 3.875024 90)
			(size 1.7272 3.4798)
			(drill oval 1.2192 2.4638)
			(layers "*.Cu" "*.Mask")
			(remove_unused_layers no)
			(net "GND")
			(clearance 0.127)
			(thermal_gap 0.127)
		)
		(pad "G3" thru_hole oval
			(at 0 68.97497 90)
			(size 1.7272 3.4798)
			(drill oval 1.2192 2.4638)
			(layers "*.Cu" "*.Mask")
			(remove_unused_layers no)
			(net "GND")
			(clearance 0.127)
			(thermal_gap 0.127)
		)
	)
)
